FILE_TYPE = CONNECTIVITY;
{Allegro Design Entry HDL 16.6-p007 (v16-6-112F) 10/10/2012}
"PAGE_NUMBER" = 189;
0"NC";
1"P3V3_STBY\g";
2"GND\g";
3"P3V3_STBY\g";
4"P3V3_STBY\g";
5"GND\g";
6"GND\g";
7"P3V3_STBY\g";
8"GND\g";
9"JTAG_TMS";
10"BMC_JTAG_SEL_N_MUX";
11"JTAG_PLD_TCK_MUX";
12"JTAG_TDI";
13"JTAG_TDI";
14"JTAG_PLD_TDO_MUX_R";
15"BMC_JTAG_SEL_N";
16"JTAG_PLD_TDO_MUX";
17"JTAG_PLD_TMS_MUX";
18"JTAG_PLD_TCK";
19"JTAG_PLD_TMS";
20"JTAG_TCK_R";
21"JTAG_TRST_N";
22"BMC_JTAG_SEL_N";
23"FM_JTAG_PLD_EN_DEBUG";
24"JTAG_BMC_TCK";
25"JTAG_TDO";
26"JTAG_TCK";
27"JTAG_TDO";
28"JTAG_TMS";
29"JTAG_TCK";
30"P3V3_STBY_PLD_D"VOLTAGE"3.3";
31"JTAG_TMS_R";
32"JTAG_TDO_R";
33"JTAG_TDI_R";
34"JTAG_PCH_PLD_TMS";
35"JTAG_PCH_GBE_CLK";
36"JTAG_BMC_TDO";
37"JTAG_PCH_PLD_TDO";
38"JTAG_PCH_GBE_TDO";
39"JTAG_PCH_PLD_TCK";
40"JTAG_BMC_TMS";
41"JTAG_PCH_GBE_TMS";
42"JTAG_BMC_TDI";
43"JTAG_PCH_PLD_TDI";
44"JTAG_PCH_GBE_TDI";
45"JTAG_BMC_TRST_N";
46"JTAG_PCH_GBE_TRST_N";
47"JTAG_TRST_N";
48"JTAG_TDO";
49"JTAG_TDI";
50"JTAG_TMS";
51"JTAG_TCK";
52"PWRGD_P3V3_STBY";
53"JTAG_PLD_TDI";
54"JTAG_PLD_TDI_MUX";
%"RES"
"1","(-2100,4225)","0","mstr_discrete","I13";
;
CDS_SEC"1"
PART_NUMBER"G21497-005"
LOCATION"R7G18"
TOLERANCE"5%"
VALUE"0.0"
MATERIAL"EMPTY"
WATTAGE"1/16W"
PACK_TYPE"0402"
SEC_TYPE"0402"
SEC"1"
CDS_LIB"mstr_discrete"
BOM_COST"DEBUG"
ROOM"BMC_DEBUG_HEADER"
CDS_LOCATION"R7G18";
"B"
$PN"2"13;
"A"
$PN"1"43;
%"RES"
"1","(-2100,4050)","0","mstr_discrete","I17";
;
CDS_SEC"1"
PACK_TYPE"0402"
LOCATION"R8G8"
MATERIAL"CHIP"
TOLERANCE"5%"
WATTAGE"1/16W"
VALUE"0.0"
PART_NUMBER"G21497-005"
SEC_TYPE"0402"
BOM_COST"DEBUG"
SEC"1"
CDS_LIB"mstr_discrete"
CDS_LOCATION"R8G8"
ROOM"BMC_DEBUG_HEADER";
"B"
$PN"2"13;
"A"
$PN"1"42;
%"RES"
"1","(-125,4650)","0","mstr_discrete","I18";
;
CDS_SEC"1"
MATERIAL"CHIP"
PACK_TYPE"0402"
TOLERANCE"5%"
WATTAGE"1/16W"
PART_NUMBER"G21497-005"
LOCATION"R8G7"
VALUE"0.0"
SEC"1"
SEC_TYPE"0402"
ROOM"BMC_DEBUG_HEADER"
BOM_COST"DEBUG"
CDS_LOCATION"R8G7"
CDS_LIB"mstr_discrete";
"B"
$PN"2"54;
"A"
$PN"1"53;
%"RES"
"1","(-2100,3500)","0","mstr_discrete","I19";
;
CDS_SEC"1"
PART_NUMBER"G21497-005"
LOCATION"R8G11"
PACK_TYPE"0402"
WATTAGE"1/16W"
MATERIAL"EMPTY"
TOLERANCE"5%"
VALUE"0.0"
SEC_TYPE"0402"
SEC"1"
BOM_COST"DEBUG"
CDS_LIB"mstr_discrete"
ROOM"BMC_DEBUG_HEADER"
CDS_LOCATION"R8G11";
"B"
$PN"2"28;
"A"
$PN"1"34;
%"RES"
"1","(-2100,3350)","0","mstr_discrete","I20";
;
CDS_SEC"1"
PART_NUMBER"G21497-005"
PACK_TYPE"0402"
MATERIAL"CHIP"
LOCATION"R8G14"
TOLERANCE"5%"
WATTAGE"1/16W"
VALUE"0.0"
SEC_TYPE"0402"
SEC"1"
ROOM"BMC_DEBUG_HEADER"
BOM_COST"DEBUG"
CDS_LIB"mstr_discrete"
CDS_LOCATION"R8G14";
"B"
$PN"2"28;
"A"
$PN"1"40;
%"RES"
"1","(-2100,3675)","0","mstr_discrete","I21";
;
CDS_SEC"1"
LOCATION"R8G12"
PART_NUMBER"G21497-005"
MATERIAL"EMPTY"
TOLERANCE"5%"
WATTAGE"1/16W"
VALUE"0.0"
PACK_TYPE"0402"
SEC_TYPE"0402"
SEC"1"
BOM_COST"DEBUG"
ROOM"BMC_DEBUG_HEADER"
CDS_LOCATION"R8G12"
CDS_LIB"mstr_discrete";
"B"
$PN"2"28;
"A"
$PN"1"41;
%"RES"
"1","(-2100,2800)","0","mstr_discrete","I22";
;
CDS_SEC"1"
PART_NUMBER"G21497-005"
PACK_TYPE"0402"
MATERIAL"EMPTY"
LOCATION"R8G16"
TOLERANCE"5%"
WATTAGE"1/16W"
VALUE"0.0"
BOM_COST"DEBUG"
SEC_TYPE"0402"
SEC"1"
ROOM"BMC_DEBUG_HEADER"
CDS_LIB"mstr_discrete"
CDS_LOCATION"R8G16";
"B"
$PN"2"29;
"A"
$PN"1"39;
%"RES"
"1","(-125,4450)","0","mstr_discrete","I23";
;
CDS_SEC"1"
VALUE"0.0"
PART_NUMBER"G21497-005"
LOCATION"R8G13"
TOLERANCE"5%"
WATTAGE"1/16W"
MATERIAL"CHIP"
PACK_TYPE"0402"
CDS_LOCATION"R8G13"
ROOM"BMC_DEBUG_HEADER"
SEC_TYPE"0402"
SEC"1"
BOM_COST"DEBUG"
CDS_LIB"mstr_discrete";
"B"
$PN"2"17;
"A"
$PN"1"19;
%"RES"
"1","(-2100,2975)","0","mstr_discrete","I24";
;
CDS_SEC"1"
PART_NUMBER"G21497-005"
PACK_TYPE"0402"
VALUE"0.0"
MATERIAL"EMPTY"
LOCATION"R8G15"
TOLERANCE"5%"
WATTAGE"1/16W"
SEC"1"
SEC_TYPE"0402"
CDS_LIB"mstr_discrete"
BOM_COST"DEBUG"
ROOM"BMC_DEBUG_HEADER"
CDS_LOCATION"R8G15";
"B"
$PN"2"29;
"A"
$PN"1"35;
%"RES"
"1","(-2100,2625)","0","mstr_discrete","I25";
;
CDS_SEC"1"
PART_NUMBER"G21497-005"
LOCATION"R8G17"
PACK_TYPE"0402"
MATERIAL"CHIP"
TOLERANCE"5%"
WATTAGE"1/16W"
VALUE"0.0"
SEC_TYPE"0402"
SEC"1"
BOM_COST"DEBUG"
CDS_LOCATION"R8G17"
ROOM"BMC_DEBUG_HEADER"
CDS_LIB"mstr_discrete";
"B"
$PN"2"29;
"A"
$PN"1"24;
%"RES"
"1","(-125,4250)","0","mstr_discrete","I26";
;
CDS_SEC"1"
TOLERANCE"5%"
PART_NUMBER"G21497-005"
LOCATION"R8G18"
VALUE"0.0"
WATTAGE"1/16W"
MATERIAL"CHIP"
PACK_TYPE"0402"
SEC_TYPE"0402"
SEC"1"
CDS_LIB"mstr_discrete"
ROOM"BMC_DEBUG_HEADER"
BOM_COST"DEBUG"
CDS_LOCATION"R8G18";
"B"
$PN"2"11;
"A"
$PN"1"18;
%"RES"
"1","(-2100,2250)","0","mstr_discrete","I27";
;
CDS_SEC"1"
PART_NUMBER"G21497-005"
PACK_TYPE"0402"
MATERIAL"EMPTY"
LOCATION"R7G16"
TOLERANCE"5%"
WATTAGE"1/16W"
VALUE"0.0"
SEC"1"
SEC_TYPE"0402"
BOM_COST"DEBUG"
CDS_LIB"mstr_discrete"
CDS_LOCATION"R7G16"
ROOM"BMC_DEBUG_HEADER";
"B"
$PN"2"25;
"A"
$PN"1"38;
%"RES"
"1","(-2100,2075)","0","mstr_discrete","I36";
;
CDS_SEC"1"
PACK_TYPE"0402"
PART_NUMBER"G21497-005"
LOCATION"R7G15"
MATERIAL"EMPTY"
TOLERANCE"5%"
WATTAGE"1/16W"
VALUE"0.0"
SEC_TYPE"0402"
SEC"1"
BOM_COST"DEBUG"
ROOM"BMC_DEBUG_HEADER"
CDS_LOCATION"R7G15"
CDS_LIB"mstr_discrete";
"B"
$PN"2"25;
"A"
$PN"1"37;
%"RES"
"1","(-2100,1900)","0","mstr_discrete","I37";
;
CDS_SEC"1"
VALUE"0.0"
WATTAGE"1/16W"
TOLERANCE"5%"
PACK_TYPE"0402"
MATERIAL"CHIP"
LOCATION"R7G17"
PART_NUMBER"G21497-005"
CDS_LOCATION"R7G17"
ROOM"BMC_DEBUG_HEADER"
SEC"1"
BOM_COST"DEBUG"
SEC_TYPE"0402"
CDS_LIB"mstr_discrete";
"B"
$PN"2"25;
"A"
$PN"1"36;
%"RES"
"1","(-125,4050)","0","mstr_discrete","I38";
;
CDS_SEC"1"
WATTAGE"1/16W"
MATERIAL"CHIP"
PACK_TYPE"0402"
LOCATION"R7G14"
PART_NUMBER"G21497-005"
VALUE"0.0"
TOLERANCE"5%"
CDS_LOCATION"R7G14"
ROOM"BMC_DEBUG_HEADER"
CDS_LIB"mstr_discrete"
BOM_COST"DEBUG"
SEC"1"
SEC_TYPE"0402";
"B"
$PN"2"16;
"A"
$PN"1"14;
%"P3V3_STBY"
"1","(175,2200)","0","mstr_symbols","I43";
;
HDL_POWER"P3V3_STBY"
BODY_TYPE"PLUMBING"
SIZE"1B"
CDS_LIB"mstr_symbols"
VOLTAGE"3.3V";
"G\NAC"1;
%"RES"
"2","(175,2000)","0","mstr_discrete","I44";
;
CDS_SEC"1"
LOCATION"R3R15"
TOLERANCE"1%"
PACK_TYPE"0402"
PART_NUMBER"G21796-026"
VALUE"1.00K"
MATERIAL"CHIP"
WATTAGE"1/16W"
SEC_TYPE"0402"
SEC"1"
CDS_LOCATION"R3R15"
ROOM"BMC_DEBUG_HEADER"
CDS_LIB"mstr_discrete";
"A"
$PN"1"1;
"B"
$PN"2"23;
%"RES"
"2","(175,1600)","0","mstr_discrete","I45";
;
CDS_SEC"1"
LOCATION"R3R11"
VALUE"10.0K"
TOLERANCE"1%"
PACK_TYPE"0402"
MATERIAL"EMPTY"
WATTAGE"1/16W"
PART_NUMBER"G21796-016"
CDS_LIB"mstr_discrete"
CDS_LOCATION"R3R11"
SEC"1"
ROOM"BMC_DEBUG_HEADER"
SEC_TYPE"0402";
"A"
$PN"1"23;
"B"
$PN"2"2;
%"GND"
"1","(175,1400)","0","mstr_symbols","I46";
;
SIZE"1B"
CDS_LIB"mstr_symbols"
VOLTAGE"0.0V"
BODY_TYPE"PLUMBING"
HDL_POWER"GND";
"A\NAC"2;
%"CONN8_C77962004"
"1","(4000,3125)","2","mstr_conn","I47";
;
CDS_SEC"1"
MATERIAL"CONN"
PART_NUMBER"C77962-004"
LOCATION"J7G2"
CDS_LOCATION"J7G2"
CDS_LIB"mstr_conn"
PACK_TYPE"PIP"
ROOM"BMC_DEBUG_HEADER"
SEC"1"
SEC_TYPE"PIP"
BOM_COST"DEBUG";
"IO1"
$PN"1"30;
"IO2"
$PN"2"32;
"IO3"
$PN"3"33;
"IO4"
$PN"4"21;
"IO5"
$PN"5"52;
"IO6"
$PN"6"31;
"IO7"
$PN"7"5;
"IO8"
$PN"8"20;
%"P3V3_STBY"
"1","(3375,3850)","0","mstr_symbols","I48";
;
SIZE"1B"
CDS_LIB"mstr_symbols"
VOLTAGE"3.3V"
BODY_TYPE"PLUMBING"
HDL_POWER"P3V3_STBY";
"G\NAC"3;
%"DIODE"
"1","(3500,3525)","0","mstr_discrete","I49";
;
CDS_SEC"1"
CDS_LOCATION"CR3U1"
PACK_TYPE"SMLF"
VALUE"1N5819HW"
PART_NUMBER"D55839-001"
MATERIAL"IC"
LOCATION"CR3U1"
BOM_COST"DEBUG"
SEC"1"
SEC_TYPE"SMLF"
ROOM"BMC_DEBUG_HEADER"
CDS_LIB"mstr_discrete";
"C"
$PN"1"30;
"A"
$PN"2"3;
%"RES"
"2","(3200,3500)","0","mstr_discrete","I50";
;
PART_NUMBER"G21796-016"
MATERIAL"CHIP"
WATTAGE"1/16W"
VALUE"10.0K"
LOCATION"R8G20"
TOLERANCE"1%"
PACK_TYPE"0402"
CDS_SEC"1"
$SEC"1"
CDS_LOCATION"R8G20"
ROOM"BMC_DEBUG_HEADER"
CDS_LIB"mstr_discrete";
"A"
$PN"1"4;
"B"
$PN"2"31;
%"RES"
"2","(2900,3500)","0","mstr_discrete","I51";
;
MATERIAL"CHIP"
PART_NUMBER"G21796-016"
VALUE"10.0K"
PACK_TYPE"0402"
LOCATION"R7G23"
TOLERANCE"1%"
WATTAGE"1/16W"
$SEC"1"
CDS_LOCATION"R7G23"
CDS_SEC"1"
ROOM"BMC_DEBUG_HEADER"
CDS_LIB"mstr_discrete";
"A"
$PN"1"4;
"B"
$PN"2"33;
%"P3V3_STBY"
"1","(2600,3875)","0","mstr_symbols","I52";
;
SIZE"1B"
CDS_LIB"mstr_symbols"
VOLTAGE"3.3V"
BODY_TYPE"PLUMBING"
HDL_POWER"P3V3_STBY";
"G\NAC"4;
%"RES"
"2","(2600,3500)","0","mstr_discrete","I53";
;
TOLERANCE"1%"
LOCATION"R7G22"
WATTAGE"1/16W"
MATERIAL"CHIP"
PART_NUMBER"G21796-016"
PACK_TYPE"0402"
VALUE"10.0K"
CDS_LIB"mstr_discrete"
ROOM"BMC_DEBUG_HEADER"
CDS_LOCATION"R7G22"
CDS_SEC"1"
$SEC"1";
"A"
$PN"1"4;
"B"
$PN"2"32;
%"GND"
"1","(3675,2800)","0","mstr_symbols","I54";
;
SIZE"1B"
VOLTAGE"0.0V"
CDS_LIB"mstr_symbols"
BODY_TYPE"PLUMBING"
HDL_POWER"GND";
"A\NAC"5;
%"GND"
"1","(3200,2475)","0","mstr_symbols","I55";
;
HDL_POWER"GND"
BODY_TYPE"PLUMBING"
SIZE"1B"
CDS_LIB"mstr_symbols"
VOLTAGE"0.0V";
"A\NAC"6;
%"RES"
"2","(3200,2700)","0","mstr_discrete","I56";
;
CDS_SEC"1"
TOLERANCE"1%"
VALUE"4.75K"
WATTAGE"1/16W"
LOCATION"R8G23"
PACK_TYPE"0402"
MATERIAL"CHIP"
PART_NUMBER"G21796-072"
ROOM"BMC_DEBUG_HEADER"
CDS_LIB"mstr_discrete"
CDS_LOCATION"R8G23"
SEC"1"
SEC_TYPE"0402";
"A"
$PN"1"20;
"B"
$PN"2"6;
%"RES"
"1","(2050,3225)","0","mstr_discrete","I63";
;
CDS_SEC"1"
PART_NUMBER"G21497-005"
LOCATION"R7G21"
MATERIAL"CHIP"
PACK_TYPE"0402"
VALUE"0.0"
TOLERANCE"5%"
WATTAGE"1/16W"
CDS_LOCATION"R7G21"
CDS_LIB"mstr_discrete"
ROOM"BMC_DEBUG_HEADER"
SEC"1"
SEC_TYPE"0402"
BOM_COST"DEBUG";
"B"
$PN"2"32;
"A"
$PN"1"48;
%"RES"
"1","(2425,3175)","0","mstr_discrete","I64";
;
CDS_SEC"1"
MATERIAL"CHIP"
WATTAGE"1/16W"
TOLERANCE"5%"
VALUE"0.0"
LOCATION"R8G19"
PART_NUMBER"G21497-005"
PACK_TYPE"0402"
SEC_TYPE"0402"
SEC"1"
BOM_COST"DEBUG"
ROOM"BMC_DEBUG_HEADER"
CDS_LOCATION"R8G19"
CDS_LIB"mstr_discrete";
"B"
$PN"2"33;
"A"
$PN"1"49;
%"RES"
"1","(2525,3025)","0","mstr_discrete","I65";
;
CDS_SEC"1"
WATTAGE"1/16W"
VALUE"0.0"
PART_NUMBER"G21497-005"
PACK_TYPE"0402"
LOCATION"R8G21"
MATERIAL"CHIP"
TOLERANCE"5%"
ROOM"BMC_DEBUG_HEADER"
SEC"1"
SEC_TYPE"0402"
BOM_COST"DEBUG"
CDS_LOCATION"R8G21"
CDS_LIB"mstr_discrete";
"B"
$PN"2"31;
"A"
$PN"1"50;
%"RES"
"1","(2850,2925)","0","mstr_discrete","I66";
;
CDS_SEC"1"
WATTAGE"1/16W"
LOCATION"R8G22"
MATERIAL"CHIP"
PART_NUMBER"G21497-005"
VALUE"0.0"
TOLERANCE"5%"
PACK_TYPE"0402"
CDS_LIB"mstr_discrete"
CDS_LOCATION"R8G22"
ROOM"BMC_DEBUG_HEADER"
BOM_COST"DEBUG"
SEC_TYPE"0402"
SEC"1";
"B"
$PN"2"20;
"A"
$PN"1"51;
%"TTL3126"
"3","(800,4300)","0","mstr_ttl","I67";
;
CDS_LOCATION"U1L10"
POWER_GROUP"VCC=P3V3_STBY;GND=GND"
PART_NUMBER"D18317-001"
VALUE"74CBTLV3126"
MATERIAL"IC"
LOCATION"U1L10"
ROOM"DEBUG"
HAS_FIXED_SIZE"4B"
PACK_TYPE"QFNLF"
CDS_LIB"mstr_ttl";
"OE <3>"
$PN"1"
$SEC"1"
CDS_SEC"1"10;
"OE <2>"
$PN"4"
$SEC"2"
CDS_SEC"2"10;
"OE <1>"
$PN"10"
$SEC"3"
CDS_SEC"3"10;
"OE <0>"
$PN"13"
$SEC"4"
CDS_SEC"4"10;
"A <3>"
$PN"2"
$SEC"1"
CDS_SEC"1"16;
"A <2>"
$PN"5"
$SEC"2"
CDS_SEC"2"11;
"A <0>"
$PN"12"
$SEC"4"
CDS_SEC"4"54;
"A <1>"
$PN"9"
$SEC"3"
CDS_SEC"3"17;
"B <3>"
$PN"3"
$SEC"1"
CDS_SEC"1"27;
"B <2>"
$PN"6"
$SEC"2"
CDS_SEC"2"26;
"B <1>"
$PN"8"
$SEC"3"
CDS_SEC"3"9;
"B <0>"
$PN"11"
$SEC"4"
CDS_SEC"4"12;
%"P3V3_STBY"
"1","(775,3700)","0","mstr_symbols","I68";
;
CDS_LIB"mstr_symbols"
VOLTAGE"+3.3V"
SIZE"1B"
BODY_TYPE"PLUMBING"
HDL_POWER"P3V3_STBY";
"G\NAC"7;
%"CAP"
"1","(775,3525)","0","mstr_discrete","I69";
;
CDS_SEC"1"
$SEC"1"
CDS_LOCATION"C1L119"
MATERIAL"X6S"
PART_NUMBER"D97712-011"
VOLTAGE"16V"
TOLERANCE"10%"
PACK_TYPE"0402"
VALUE"1.0UF"
LOCATION"C1L119"
ROOM"DEBUG"
CDS_LIB"mstr_discrete";
"A"
$PN"1"7;
"B"
$PN"2"8;
%"RES"
"1","(-2100,4775)","0","mstr_discrete","I7";
;
CDS_SEC"1"
PART_NUMBER"G21497-005"
PACK_TYPE"0402"
VALUE"0.0"
LOCATION"R8G10"
MATERIAL"CHIP"
TOLERANCE"5%"
WATTAGE"1/16W"
SEC_TYPE"0402"
SEC"1"
BOM_COST"DEBUG"
CDS_LIB"mstr_discrete"
CDS_LOCATION"R8G10"
ROOM"BMC_DEBUG_HEADER";
"B"
$PN"2"47;
"A"
$PN"1"45;
%"GND"
"1","(775,3350)","0","mstr_symbols","I70";
;
CDS_LIB"mstr_symbols"
VOLTAGE"0.0V"
SIZE"1B"
BODY_TYPE"PLUMBING"
HDL_POWER"GND";
"A\NAC"8;
%"RES"
"1","(-100,3800)","0","mstr_discrete","I76";
;
CDS_SEC"1"
$SEC"1"
CDS_LOCATION"R7G114"
LOCATION"R7G114"
MATERIAL"CHIP"
VALUE"0.0"
TOLERANCE"5%"
WATTAGE"1/16W"
PART_NUMBER"G21497-005"
PACK_TYPE"0402"
CDS_LIB"mstr_discrete"
BOM_COST"DEBUG"
ROOM"BMC_DEBUG_HEADER";
"B"
$PN"2"10;
"A"
$PN"1"15;
%"RES"
"1","(-50,1800)","0","mstr_discrete","I77";
;
CDS_SEC"1"
MATERIAL"CHIP"
PACK_TYPE"0402"
PART_NUMBER"G21497-005"
TOLERANCE"5%"
WATTAGE"1/16W"
VALUE"0.0"
LOCATION"R25W186"
CDS_LIB"mstr_discrete"
SEC_TYPE"0402"
BOM_COST"DEBUG"
SEC"1"
ROOM"BMC_DEBUG_HEADER"
CDS_LOCATION"R25W186";
"B"
$PN"2"23;
"A"
$PN"1"22;
%"RES"
"1","(-2100,4400)","0","mstr_discrete","I8";
;
CDS_SEC"1"
PART_NUMBER"G21497-005"
LOCATION"R7G19"
PACK_TYPE"0402"
MATERIAL"EMPTY"
TOLERANCE"5%"
WATTAGE"1/16W"
VALUE"0.0"
SEC_TYPE"0402"
SEC"1"
BOM_COST"DEBUG"
ROOM"BMC_DEBUG_HEADER"
CDS_LOCATION"R7G19"
CDS_LIB"mstr_discrete";
"B"
$PN"2"13;
"A"
$PN"1"44;
%"RES"
"1","(-2100,4600)","0","mstr_discrete","I9";
;
PART_NUMBER"G21497-005"
PACK_TYPE"0402"
LOCATION"R8G9"
TOLERANCE"5%"
VALUE"0.0"
WATTAGE"1/16W"
MATERIAL"EMPTY"
$SEC"1"
CDS_SEC"1"
BOM_COST"DEBUG"
ROOM"BMC_DEBUG_HEADER"
CDS_LIB"mstr_discrete"
CDS_LOCATION"R8G9";
"B"
$PN"2"47;
"A"
$PN"1"46;
END.
